FILE_TYPE = CONNECTIVITY;
{Allegro Design Entry HDL 16.6-p007 (v16-6-112F) 10/10/2012}
"PAGE_NUMBER" = 2;
0"NC";
END.
